# BASEBOARD_FAB2 (Tioga Pass) — schematic netlist excerpt (pin names and nets, part order shuffled) for the footprints in the layout excerpt that follows; sources: Cadence DE-HDL packaged netlist, KiCad conversion of Wiwynn_Tioga_Pass_MB.brd

C8P18  CAP  47UF 4V 20% X6S  pkg 0805  page 76 : A = PVCCIN_CPU1 ; B = GND
R25W67  200R2F-L1-GP  1%  pkg SMD-RG4  page 145 : \1\ = PD_PEREXT ; \2\ = GND
C4U3  CAP  10UF 4V 20% X6S  pkg 0603LF  page 231 : A = PVPP_ABC ; B = GND

(kicad_pcb
	(version 20260206)
	(generator "pcbnew")
	(generator_version "10.0")
	(general
		(thickness 1.6)
		(legacy_teardrops no)
	)
	(paper "A4")
	(title_block
		(title "Wiwynn_Tioga_Pass_MB.brd")
		(comment 1 "Tioga Pass / footprints 3625-3627 of 4770")
	)
	(layers
		(0 "F.Cu" signal "TOP")
		(4 "In1.Cu" signal "L2GND")
		(6 "In2.Cu" signal "L3")
		(8 "In3.Cu" signal "L4GND")
		(10 "In4.Cu" signal "L5")
		(12 "In5.Cu" signal "L6GND")
		(14 "In6.Cu" signal "L7VCC")
		(16 "In7.Cu" signal "L8VCC")
		(18 "In8.Cu" signal "L9GND")
		(20 "In9.Cu" signal "L10")
		(22 "In10.Cu" signal "L11GND")
		(24 "In11.Cu" signal "L12")
		(26 "In12.Cu" signal "L13GND")
		(2 "B.Cu" signal "BOTTOM")
		(9 "F.Adhes" user "F.Adhesive")
		(11 "B.Adhes" user "B.Adhesive")
		(13 "F.Paste" user "Package Geometry/Pastemask Top")
		(15 "B.Paste" user "Package Geometry/Pastemask Bottom")
		(5 "F.SilkS" user "Ref Des/Silkscreen Top")
		(7 "B.SilkS" user "Ref Des/Silkscreen Bottom")
		(1 "F.Mask" user "Board Geometry/Soldermask Top")
		(3 "B.Mask" user "Board Geometry/Soldermask Bottom")
		(17 "Dwgs.User" user "User.Drawings")
		(19 "Cmts.User" user "User.Comments")
		(21 "Eco1.User" user "User.Eco1")
		(23 "Eco2.User" user "User.Eco2")
		(25 "Edge.Cuts" user "Board Geometry/Outline")
		(27 "Margin" user)
		(31 "F.CrtYd" user "Package Geometry/Place Bound Top")
		(29 "B.CrtYd" user "Package Geometry/Place Bound Bottom")
		(35 "F.Fab" user "Ref Des/Assembly Top")
		(33 "B.Fab" user "Ref Des/Assembly Bottom")
	)
	(footprint ""
		(layer "B.Cu")
		(at 99.034854 -77.82814)
		(property "Reference" "C8P18"
			(at 0 0 0)
			(layer "B.SilkS")
			(hide yes)
			(effects
				(font
					(size 1.27 1.27)
				)
				(justify mirror)
			)
		)
		(property "Value" ""
			(at 0 0 0)
			(layer "B.Fab")
			(effects
				(font
					(size 1.27 1.27)
				)
				(justify mirror)
			)
		)
		(duplicate_pad_numbers_are_jumpers no)
		(fp_poly
			(pts
				(xy 0.7239 -0.2159) (xy -0.7239 -0.2159) (xy -0.7239 1.9939) (xy 0.7239 1.9939)
			)
			(stroke
				(width 0)
				(type default)
			)
			(fill no)
			(layer "B.CrtYd")
		)
		(fp_line
			(start -0.7239 -0.2159)
			(end 0.7239 -0.2159)
			(stroke
				(width 0.1)
				(type default)
			)
			(layer "B.Fab")
		)
		(fp_line
			(start -0.7239 1.9939)
			(end -0.7239 -0.2159)
			(stroke
				(width 0.1)
				(type default)
			)
			(layer "B.Fab")
		)
		(fp_line
			(start 0.7239 -0.2159)
			(end 0.7239 1.9939)
			(stroke
				(width 0.1)
				(type default)
			)
			(layer "B.Fab")
		)
		(fp_line
			(start 0.7239 1.9939)
			(end -0.7239 1.9939)
			(stroke
				(width 0.1)
				(type default)
			)
			(layer "B.Fab")
		)
		(pad "1" smd rect
			(at 0 0 180)
			(size 1.27 1.016)
			(layers "B.Cu" "B.Mask" "B.Paste")
			(net "PVCCIN_CPU1")
		)
		(pad "2" smd rect
			(at 0 1.778 180)
			(size 1.27 1.016)
			(layers "B.Cu" "B.Mask" "B.Paste")
			(net "GND")
		)
		(zone
			(layer "B.Cu")
			(hatch none 0.5)
			(connect_pads
				(clearance 0)
			)
			(min_thickness 0.25)
			(keepout
				(tracks not_allowed)
				(vias allowed)
				(pads allowed)
				(copperpour not_allowed)
				(footprints allowed)
			)
			(placement
				(enabled no)
				(sheetname "")
			)
			(fill
				(thermal_gap 0.5)
				(thermal_bridge_width 0.5)
				(island_removal_mode 0)
			)
			(polygon
				(pts
					(xy 99.669854 -77.32014) (xy 98.399854 -77.32014) (xy 98.399854 -76.55814) (xy 99.669854 -76.55814)
				)
			)
		)
	)
	(footprint ""
		(layer "B.Cu")
		(at 320.194432 1.7018 90)
		(property "Reference" "C4U3"
			(at 0 0 90)
			(layer "B.SilkS")
			(hide yes)
			(effects
				(font
					(size 1.27 1.27)
				)
				(justify mirror)
			)
		)
		(property "Value" ""
			(at 0 0 90)
			(layer "B.Fab")
			(effects
				(font
					(size 1.27 1.27)
				)
				(justify mirror)
			)
		)
		(duplicate_pad_numbers_are_jumpers no)
		(fp_poly
			(pts
				(xy 0.4953 -0.2032) (xy -0.4953 -0.2032) (xy -0.4953 1.6002) (xy 0.4953 1.6002)
			)
			(stroke
				(width 0)
				(type default)
			)
			(fill no)
			(layer "B.CrtYd")
		)
		(fp_line
			(start 0.4953 -0.2032)
			(end -0.4953 -0.2032)
			(stroke
				(width 0.1)
				(type default)
			)
			(layer "B.Fab")
		)
		(fp_line
			(start -0.4953 -0.2032)
			(end -0.4953 1.6002)
			(stroke
				(width 0.1)
				(type default)
			)
			(layer "B.Fab")
		)
		(fp_line
			(start 0.4953 1.6002)
			(end 0.4953 -0.2032)
			(stroke
				(width 0.1)
				(type default)
			)
			(layer "B.Fab")
		)
		(fp_line
			(start -0.4953 1.6002)
			(end 0.4953 1.6002)
			(stroke
				(width 0.1)
				(type default)
			)
			(layer "B.Fab")
		)
		(pad "1" smd rect
			(at 0 0 270)
			(size 0.762 0.889)
			(layers "B.Cu" "B.Mask" "B.Paste")
			(net "PVPP_ABC")
		)
		(pad "2" smd rect
			(at 0 1.397 270)
			(size 0.762 0.889)
			(layers "B.Cu" "B.Mask" "B.Paste")
			(net "GND")
		)
		(zone
			(layer "B.Cu")
			(hatch none 0.5)
			(connect_pads
				(clearance 0)
			)
			(min_thickness 0.25)
			(keepout
				(tracks not_allowed)
				(vias allowed)
				(pads allowed)
				(copperpour not_allowed)
				(footprints allowed)
			)
			(placement
				(enabled no)
				(sheetname "")
			)
			(fill
				(thermal_gap 0.5)
				(thermal_bridge_width 0.5)
				(island_removal_mode 0)
			)
			(polygon
				(pts
					(xy 320.638932 1.3208) (xy 320.638932 2.0828) (xy 321.146932 2.0828) (xy 321.146932 1.3208)
				)
			)
		)
	)
	(footprint ""
		(layer "B.Cu")
		(at 412.877 -43.053 90)
		(property "Reference" "R25W67"
			(at 0 0 90)
			(layer "B.SilkS")
			(hide yes)
			(effects
				(font
					(size 1.27 1.27)
				)
				(justify mirror)
			)
		)
		(property "Value" "*"
			(at -0.064008 -4.108196 90)
			(unlocked yes)
			(layer "B.Fab")
			(hide yes)
			(effects
				(font
					(size 1.27 1.016)
					(thickness 0.1524)
				)
				(justify mirror)
			)
		)
		(property "Device Type" "200R2F-L1-GP_SMD-RG4-200R2F-L1A"
			(at -0.064008 -5.632196 90)
			(unlocked yes)
			(layer "B.Fab")
			(hide yes)
			(effects
				(font
					(size 1.27 1.016)
					(thickness 0.1524)
				)
				(justify mirror)
			)
		)
		(duplicate_pad_numbers_are_jumpers no)
		(fp_line
			(start 0.508 -0.9398)
			(end 0.508 0.9398)
			(stroke
				(width 0.1524)
				(type default)
			)
			(layer "B.SilkS")
		)
		(fp_line
			(start -0.508 -0.9398)
			(end 0.508 -0.9398)
			(stroke
				(width 0.1524)
				(type default)
			)
			(layer "B.SilkS")
		)
		(fp_rect
			(start 0.508 0.9398)
			(end -0.508 -0.9398)
			(stroke
				(width 0)
				(type default)
			)
			(fill no)
			(layer "B.CrtYd")
		)
		(fp_rect
			(start 0.508 0.9398)
			(end -0.508 -0.9398)
			(stroke
				(width 0)
				(type default)
			)
			(fill no)
			(layer "B.Fab")
		)
		(pad "1" smd custom
			(at 0 -0.4445 270)
			(size 0.1397 0.1397)
			(layers "B.Cu" "B.Mask" "B.Paste")
			(net "PD_PEREXT")
			(options
				(clearance outline)
				(anchor circle)
			)
			(primitives
				(gr_poly
					(pts
						(arc
							(start -0.1778 0.2794)
							(mid -0.249642 0.249642)
							(end -0.2794 0.1778)
						)
						(arc
							(start -0.2794 -0.1778)
							(mid -0.249642 -0.249642)
							(end -0.1778 -0.2794)
						)
						(arc
							(start 0.1778 -0.2794)
							(mid 0.249642 -0.249642)
							(end 0.2794 -0.1778)
						)
						(arc
							(start 0.2794 0.1778)
							(mid 0.249642 0.249642)
							(end 0.1778 0.2794)
						)
					)
					(width 0)
					(fill yes)
				)
			)
		)
		(pad "2" smd custom
			(at 0 0.4445 270)
			(size 0.1397 0.1397)
			(layers "B.Cu" "B.Mask" "B.Paste")
			(net "GND")
			(options
				(clearance outline)
				(anchor circle)
			)
			(primitives
				(gr_poly
					(pts
						(arc
							(start -0.1778 0.2794)
							(mid -0.249642 0.249642)
							(end -0.2794 0.1778)
						)
						(arc
							(start -0.2794 -0.1778)
							(mid -0.249642 -0.249642)
							(end -0.1778 -0.2794)
						)
						(arc
							(start 0.1778 -0.2794)
							(mid 0.249642 -0.249642)
							(end 0.2794 -0.1778)
						)
						(arc
							(start 0.2794 0.1778)
							(mid 0.249642 0.249642)
							(end 0.1778 0.2794)
						)
					)
					(width 0)
					(fill yes)
				)
			)
		)
	)
)
